# BASEBOARD_FAB2 (Tioga Pass) — schematic netlist excerpt (pin names and nets, part order shuffled) for the footprints in the layout excerpt that follows; sources: Cadence DE-HDL packaged netlist, KiCad conversion of Wiwynn_Tioga_Pass_MB.brd

R8F10  RES  22.1 1.0% CHIP  pkg 0402  page 240 : A = PWRGD_P3V3_STBY_R ; B = PWRGD_P3V3_STBY
R6D11  RES  49.9 1% CHIP  pkg 0402  page 21 : A = A_CPU0_UPI01_RBIAS ; B = GND
C3D5  CAP_A  22.0UF 4V 20% X6S  pkg 0603V  page 76 : A = PVCCMCP_CPU1 ; B = GND

(kicad_pcb
	(version 20260206)
	(generator "pcbnew")
	(generator_version "10.0")
	(general
		(thickness 1.6)
		(legacy_teardrops no)
	)
	(paper "A4")
	(title_block
		(title "Wiwynn_Tioga_Pass_MB.brd")
		(comment 1 "Tioga Pass / footprints 16-18 of 4770")
	)
	(layers
		(0 "F.Cu" signal "TOP")
		(4 "In1.Cu" signal "L2GND")
		(6 "In2.Cu" signal "L3")
		(8 "In3.Cu" signal "L4GND")
		(10 "In4.Cu" signal "L5")
		(12 "In5.Cu" signal "L6GND")
		(14 "In6.Cu" signal "L7VCC")
		(16 "In7.Cu" signal "L8VCC")
		(18 "In8.Cu" signal "L9GND")
		(20 "In9.Cu" signal "L10")
		(22 "In10.Cu" signal "L11GND")
		(24 "In11.Cu" signal "L12")
		(26 "In12.Cu" signal "L13GND")
		(2 "B.Cu" signal "BOTTOM")
		(9 "F.Adhes" user "F.Adhesive")
		(11 "B.Adhes" user "B.Adhesive")
		(13 "F.Paste" user "Package Geometry/Pastemask Top")
		(15 "B.Paste" user "Package Geometry/Pastemask Bottom")
		(5 "F.SilkS" user "Ref Des/Silkscreen Top")
		(7 "B.SilkS" user "Ref Des/Silkscreen Bottom")
		(1 "F.Mask" user "Board Geometry/Soldermask Top")
		(3 "B.Mask" user "Board Geometry/Soldermask Bottom")
		(17 "Dwgs.User" user "User.Drawings")
		(19 "Cmts.User" user "User.Comments")
		(21 "Eco1.User" user "User.Eco1")
		(23 "Eco2.User" user "User.Eco2")
		(25 "Edge.Cuts" user "Board Geometry/Outline")
		(27 "Margin" user)
		(31 "F.CrtYd" user "Package Geometry/Place Bound Top")
		(29 "B.CrtYd" user "Package Geometry/Place Bound Bottom")
		(35 "F.Fab" user "Ref Des/Assembly Top")
		(33 "B.Fab" user "Ref Des/Assembly Bottom")
	)
	(footprint ""
		(layer "F.Cu")
		(at 464.7946 -21.3233)
		(property "Reference" "R8F10"
			(at 0 0 0)
			(layer "F.SilkS")
			(hide yes)
			(effects
				(font
					(size 1.27 1.27)
				)
			)
		)
		(property "Value" ""
			(at 0 0 0)
			(layer "F.Fab")
			(effects
				(font
					(size 1.27 1.27)
				)
			)
		)
		(duplicate_pad_numbers_are_jumpers no)
		(fp_poly
			(pts
				(xy -0.2794 -0.1016) (xy 0.2794 -0.1016) (xy 0.2794 0.9906) (xy -0.2794 0.9906)
			)
			(stroke
				(width 0)
				(type default)
			)
			(fill no)
			(layer "F.CrtYd")
		)
		(fp_line
			(start -0.2794 -0.1016)
			(end -0.2794 0.9906)
			(stroke
				(width 0.1)
				(type default)
			)
			(layer "F.Fab")
		)
		(fp_line
			(start -0.2794 0.9906)
			(end 0.2794 0.9906)
			(stroke
				(width 0.1)
				(type default)
			)
			(layer "F.Fab")
		)
		(fp_line
			(start 0.2794 -0.1016)
			(end -0.2794 -0.1016)
			(stroke
				(width 0.1)
				(type default)
			)
			(layer "F.Fab")
		)
		(fp_line
			(start 0.2794 0.9906)
			(end 0.2794 -0.1016)
			(stroke
				(width 0.1)
				(type default)
			)
			(layer "F.Fab")
		)
		(pad "1" smd rect
			(at 0 0)
			(size 0.508 0.508)
			(layers "F.Cu" "F.Mask" "F.Paste")
			(net "PWRGD_P3V3_STBY_R")
		)
		(pad "2" smd rect
			(at 0 0.889)
			(size 0.508 0.508)
			(layers "F.Cu" "F.Mask" "F.Paste")
			(net "PWRGD_P3V3_STBY")
		)
		(zone
			(layer "F.Cu")
			(hatch none 0.5)
			(connect_pads
				(clearance 0)
			)
			(min_thickness 0.25)
			(keepout
				(tracks allowed)
				(vias not_allowed)
				(pads allowed)
				(copperpour not_allowed)
				(footprints allowed)
			)
			(placement
				(enabled no)
				(sheetname "")
			)
			(fill
				(thermal_gap 0.5)
				(thermal_bridge_width 0.5)
				(island_removal_mode 0)
			)
			(polygon
				(pts
					(xy 464.5406 -21.0693) (xy 465.0486 -21.0693) (xy 465.0486 -20.6883) (xy 464.5406 -20.6883)
				)
			)
		)
		(zone
			(layer "F.Cu")
			(hatch none 0.5)
			(connect_pads
				(clearance 0)
			)
			(min_thickness 0.25)
			(keepout
				(tracks not_allowed)
				(vias allowed)
				(pads allowed)
				(copperpour not_allowed)
				(footprints allowed)
			)
			(placement
				(enabled no)
				(sheetname "")
			)
			(fill
				(thermal_gap 0.5)
				(thermal_bridge_width 0.5)
				(island_removal_mode 0)
			)
			(polygon
				(pts
					(xy 464.5406 -20.6883) (xy 465.0486 -20.6883) (xy 465.0486 -21.0693) (xy 464.5406 -21.0693)
				)
			)
		)
	)
	(footprint ""
		(layer "F.Cu")
		(at 109.522768 -79.6036 180)
		(property "Reference" "C3D5"
			(at 0 0 180)
			(layer "F.SilkS")
			(hide yes)
			(effects
				(font
					(size 1.27 1.27)
				)
			)
		)
		(property "Value" ""
			(at 0 0 180)
			(layer "F.Fab")
			(effects
				(font
					(size 1.27 1.27)
				)
			)
		)
		(duplicate_pad_numbers_are_jumpers no)
		(fp_poly
			(pts
				(xy -0.4953 -0.2032) (xy 0.4953 -0.2032) (xy 0.4953 1.6002) (xy -0.4953 1.6002)
			)
			(stroke
				(width 0)
				(type default)
			)
			(fill no)
			(layer "F.CrtYd")
		)
		(fp_line
			(start 0.4953 1.6002)
			(end -0.4953 1.6002)
			(stroke
				(width 0.1)
				(type default)
			)
			(layer "F.Fab")
		)
		(fp_line
			(start 0.4953 -0.2032)
			(end 0.4953 1.6002)
			(stroke
				(width 0.1)
				(type default)
			)
			(layer "F.Fab")
		)
		(fp_line
			(start -0.4953 1.6002)
			(end -0.4953 -0.2032)
			(stroke
				(width 0.1)
				(type default)
			)
			(layer "F.Fab")
		)
		(fp_line
			(start -0.4953 -0.2032)
			(end 0.4953 -0.2032)
			(stroke
				(width 0.1)
				(type default)
			)
			(layer "F.Fab")
		)
		(pad "1" smd rect
			(at 0 0 180)
			(size 0.762 0.889)
			(layers "F.Cu" "F.Mask" "F.Paste")
			(net "PVCCMCP_CPU1")
		)
		(pad "2" smd rect
			(at 0 1.397 180)
			(size 0.762 0.889)
			(layers "F.Cu" "F.Mask" "F.Paste")
			(net "GND")
		)
		(zone
			(layer "F.Cu")
			(hatch none 0.5)
			(connect_pads
				(clearance 0)
			)
			(min_thickness 0.25)
			(keepout
				(tracks not_allowed)
				(vias allowed)
				(pads allowed)
				(copperpour not_allowed)
				(footprints allowed)
			)
			(placement
				(enabled no)
				(sheetname "")
			)
			(fill
				(thermal_gap 0.5)
				(thermal_bridge_width 0.5)
				(island_removal_mode 0)
			)
			(polygon
				(pts
					(xy 109.903768 -80.0481) (xy 109.141768 -80.0481) (xy 109.141768 -80.5561) (xy 109.903768 -80.5561)
				)
			)
		)
	)
	(footprint ""
		(layer "F.Cu")
		(at 282.030424 -71.460614 -90)
		(property "Reference" "R6D11"
			(at 0 0 270)
			(layer "F.SilkS")
			(hide yes)
			(effects
				(font
					(size 1.27 1.27)
				)
			)
		)
		(property "Value" ""
			(at 0 0 270)
			(layer "F.Fab")
			(effects
				(font
					(size 1.27 1.27)
				)
			)
		)
		(duplicate_pad_numbers_are_jumpers no)
		(fp_rect
			(start 0.2794 0.9906)
			(end -0.2794 -0.1016)
			(stroke
				(width 0)
				(type default)
			)
			(fill no)
			(layer "F.CrtYd")
		)
		(fp_line
			(start -0.2794 0.9906)
			(end 0.2794 0.9906)
			(stroke
				(width 0.1)
				(type default)
			)
			(layer "F.Fab")
		)
		(fp_line
			(start 0.2794 0.9906)
			(end 0.2794 -0.1016)
			(stroke
				(width 0.1)
				(type default)
			)
			(layer "F.Fab")
		)
		(fp_line
			(start -0.2794 -0.1016)
			(end -0.2794 0.9906)
			(stroke
				(width 0.1)
				(type default)
			)
			(layer "F.Fab")
		)
		(fp_line
			(start 0.2794 -0.1016)
			(end -0.2794 -0.1016)
			(stroke
				(width 0.1)
				(type default)
			)
			(layer "F.Fab")
		)
		(pad "1" smd rect
			(at 0 0 270)
			(size 0.508 0.508)
			(layers "F.Cu" "F.Mask" "F.Paste")
			(net "A_CPU0_UPI01_RBIAS")
		)
		(pad "2" smd rect
			(at 0 0.889 270)
			(size 0.508 0.508)
			(layers "F.Cu" "F.Mask" "F.Paste")
			(net "GND")
		)
		(zone
			(layer "F.Cu")
			(hatch none 0.5)
			(connect_pads
				(clearance 0)
			)
			(min_thickness 0.25)
			(keepout
				(tracks not_allowed)
				(vias allowed)
				(pads allowed)
				(copperpour not_allowed)
				(footprints allowed)
			)
			(placement
				(enabled no)
				(sheetname "")
			)
			(fill
				(thermal_gap 0.5)
				(thermal_bridge_width 0.5)
				(island_removal_mode 0)
			)
			(polygon
				(pts
					(xy 281.395424 -71.206614) (xy 281.776424 -71.206614) (xy 281.776424 -71.714614) (xy 281.395424 -71.714614)
				)
			)
		)
		(zone
			(layer "F.Cu")
			(hatch none 0.5)
			(connect_pads
				(clearance 0)
			)
			(min_thickness 0.25)
			(keepout
				(tracks allowed)
				(vias not_allowed)
				(pads allowed)
				(copperpour not_allowed)
				(footprints allowed)
			)
			(placement
				(enabled no)
				(sheetname "")
			)
			(fill
				(thermal_gap 0.5)
				(thermal_bridge_width 0.5)
				(island_removal_mode 0)
			)
			(polygon
				(pts
					(xy 281.395424 -71.206614) (xy 281.776424 -71.206614) (xy 281.776424 -71.714614) (xy 281.395424 -71.714614)
				)
			)
		)
	)
)
